(kicad_pcb
	(version 20260206)
	(generator "pcbnew")
	(generator_version "10.0")
	(general
		(thickness 1.6)
		(legacy_teardrops no)
	)
	(paper "A4")
	(title_block
		(title "03242023_DA0F0TMBIJ0_F0T_Motherboard_J_brd_V01_OCP.brd")
		(comment 1 "Grand Teton / footprints 5041-5045 of 6105")
	)
	(layers
		(0 "F.Cu" signal "TOP")
		(4 "In1.Cu" signal "GND")
		(6 "In2.Cu" signal "IN1")
		(8 "In3.Cu" signal "GND1")
		(10 "In4.Cu" signal "IN2")
		(12 "In5.Cu" signal "GND2")
		(14 "In6.Cu" signal "IN3")
		(16 "In7.Cu" signal "GND3")
		(18 "In8.Cu" signal "VCC")
		(20 "In9.Cu" signal "VCC1")
		(22 "In10.Cu" signal "GND4")
		(24 "In11.Cu" signal "IN4")
		(26 "In12.Cu" signal "GND5")
		(28 "In13.Cu" signal "IN5")
		(30 "In14.Cu" signal "GND6")
		(32 "In15.Cu" signal "IN6")
		(34 "In16.Cu" signal "GND7")
		(2 "B.Cu" signal "BOTTOM")
		(9 "F.Adhes" user "F.Adhesive")
		(11 "B.Adhes" user "B.Adhesive")
		(13 "F.Paste" user "Package Geometry/Pastemask Top")
		(15 "B.Paste" user "Package Geometry/Pastemask Bottom")
		(5 "F.SilkS" user "Ref Des/Silkscreen Top")
		(7 "B.SilkS" user "Ref Des/Silkscreen Bottom")
		(1 "F.Mask" user "Board Geometry/Soldermask Top")
		(3 "B.Mask" user "Board Geometry/Soldermask Bottom")
		(17 "Dwgs.User" user "User.Drawings")
		(19 "Cmts.User" user "User.Comments")
		(21 "Eco1.User" user "User.Eco1")
		(23 "Eco2.User" user "User.Eco2")
		(25 "Edge.Cuts" user "Board Geometry/Outline")
		(27 "Margin" user)
		(31 "F.CrtYd" user "Package Geometry/Place Bound Top")
		(29 "B.CrtYd" user "Package Geometry/Place Bound Bottom")
		(35 "F.Fab" user "Ref Des/Assembly Top")
		(33 "B.Fab" user "Ref Des/Assembly Bottom")
	)
	(footprint ""
		(layer "B.Cu")
		(at 305.181 -317.159386 45)
		(property "Reference" "R3876"
			(at 0 0 45)
			(layer "B.SilkS")
			(hide yes)
			(effects
				(font
					(size 1.27 1.27)
				)
				(justify mirror)
			)
		)
		(property "Value" ""
			(at 0 0 45)
			(layer "B.Fab")
			(effects
				(font
					(size 1.27 1.27)
				)
				(justify mirror)
			)
		)
		(duplicate_pad_numbers_are_jumpers no)
		(fp_line
			(start -0.787389 -0.406267)
			(end -0.787389 0.406267)
			(stroke
				(width 0.1524)
				(type default)
			)
			(layer "B.SilkS")
		)
		(fp_line
			(start -0.787389 0.406267)
			(end 0.787389 0.406267)
			(stroke
				(width 0.1524)
				(type default)
			)
			(layer "B.SilkS")
		)
		(fp_line
			(start 0.787389 -0.406267)
			(end -0.787389 -0.406267)
			(stroke
				(width 0.1524)
				(type default)
			)
			(layer "B.SilkS")
		)
		(fp_line
			(start 0.787389 0.406267)
			(end 0.787389 -0.406267)
			(stroke
				(width 0.1524)
				(type default)
			)
			(layer "B.SilkS")
		)
		(fp_line
			(start -0.679446 -0.30479)
			(end -0.679446 0.30479)
			(stroke
				(width 0.1)
				(type default)
			)
			(layer "B.Fab")
		)
		(fp_line
			(start -0.120515 -0.30479)
			(end -0.679446 -0.30479)
			(stroke
				(width 0.1)
				(type default)
			)
			(layer "B.Fab")
		)
		(fp_line
			(start -0.120695 -0.279466)
			(end -0.120515 -0.30479)
			(stroke
				(width 0.1)
				(type default)
			)
			(layer "B.Fab")
		)
		(fp_line
			(start -0.679446 0.30479)
			(end -0.120515 0.30479)
			(stroke
				(width 0.1)
				(type default)
			)
			(layer "B.Fab")
		)
		(fp_line
			(start 0.120695 -0.304969)
			(end 0.120695 -0.279466)
			(stroke
				(width 0.1)
				(type default)
			)
			(layer "B.Fab")
		)
		(fp_line
			(start 0.120695 -0.279466)
			(end -0.120695 -0.279466)
			(stroke
				(width 0.1)
				(type default)
			)
			(layer "B.Fab")
		)
		(fp_line
			(start -0.120335 0.279466)
			(end 0.120695 0.279466)
			(stroke
				(width 0.1)
				(type default)
			)
			(layer "B.Fab")
		)
		(fp_line
			(start -0.120515 0.30479)
			(end -0.120335 0.279466)
			(stroke
				(width 0.1)
				(type default)
			)
			(layer "B.Fab")
		)
		(fp_line
			(start 0.679446 -0.305149)
			(end 0.120695 -0.304969)
			(stroke
				(width 0.1)
				(type default)
			)
			(layer "B.Fab")
		)
		(fp_line
			(start 0.120695 0.279466)
			(end 0.120515 0.30479)
			(stroke
				(width 0.1)
				(type default)
			)
			(layer "B.Fab")
		)
		(fp_line
			(start 0.120515 0.30479)
			(end 0.679446 0.30479)
			(stroke
				(width 0.1)
				(type default)
			)
			(layer "B.Fab")
		)
		(fp_line
			(start 0.679446 0.30479)
			(end 0.679446 -0.305149)
			(stroke
				(width 0.1)
				(type default)
			)
			(layer "B.Fab")
		)
		(pad "1" smd circle
			(at 0.40005 0 225)
			(size 0 0)
			(layers "B.Cu" "B.Mask" "B.Paste")
			(net "I3C_SPD_DDRABCD_CPU0_LVC1_SCL_1")
		)
		(pad "2" smd circle
			(at -0.40005 0 225)
			(size 0 0)
			(layers "B.Cu" "B.Mask" "B.Paste")
			(net "I3C_SPD_DDRABCD_CPU0_LVC1_SCL")
		)
	)
	(footprint ""
		(layer "B.Cu")
		(at 238.75238 -132.508752 90)
		(property "Reference" "R4502"
			(at 0 0 90)
			(layer "B.SilkS")
			(hide yes)
			(effects
				(font
					(size 1.27 1.27)
				)
				(justify mirror)
			)
		)
		(property "Value" ""
			(at 0 0 90)
			(layer "B.Fab")
			(effects
				(font
					(size 1.27 1.27)
				)
				(justify mirror)
			)
		)
		(duplicate_pad_numbers_are_jumpers no)
		(fp_line
			(start 0.7874 -0.4064)
			(end -0.7874 -0.4064)
			(stroke
				(width 0.1524)
				(type default)
			)
			(layer "B.SilkS")
		)
		(fp_line
			(start -0.7874 -0.4064)
			(end -0.7874 0.4064)
			(stroke
				(width 0.1524)
				(type default)
			)
			(layer "B.SilkS")
		)
		(fp_line
			(start 0.7874 0.4064)
			(end 0.7874 -0.4064)
			(stroke
				(width 0.1524)
				(type default)
			)
			(layer "B.SilkS")
		)
		(fp_line
			(start -0.7874 0.4064)
			(end 0.7874 0.4064)
			(stroke
				(width 0.1524)
				(type default)
			)
			(layer "B.SilkS")
		)
		(fp_line
			(start 0.67945 -0.305054)
			(end 0.12065 -0.305054)
			(stroke
				(width 0.1)
				(type default)
			)
			(layer "B.Fab")
		)
		(fp_line
			(start 0.12065 -0.305054)
			(end 0.12065 -0.2794)
			(stroke
				(width 0.1)
				(type default)
			)
			(layer "B.Fab")
		)
		(fp_line
			(start -0.12065 -0.3048)
			(end -0.67945 -0.3048)
			(stroke
				(width 0.1)
				(type default)
			)
			(layer "B.Fab")
		)
		(fp_line
			(start -0.67945 -0.3048)
			(end -0.67945 0.3048)
			(stroke
				(width 0.1)
				(type default)
			)
			(layer "B.Fab")
		)
		(fp_line
			(start 0.12065 -0.2794)
			(end -0.12065 -0.2794)
			(stroke
				(width 0.1)
				(type default)
			)
			(layer "B.Fab")
		)
		(fp_line
			(start -0.12065 -0.2794)
			(end -0.12065 -0.3048)
			(stroke
				(width 0.1)
				(type default)
			)
			(layer "B.Fab")
		)
		(fp_line
			(start 0.12065 0.2794)
			(end 0.12065 0.3048)
			(stroke
				(width 0.1)
				(type default)
			)
			(layer "B.Fab")
		)
		(fp_line
			(start -0.120396 0.2794)
			(end 0.12065 0.2794)
			(stroke
				(width 0.1)
				(type default)
			)
			(layer "B.Fab")
		)
		(fp_line
			(start 0.67945 0.3048)
			(end 0.67945 -0.305054)
			(stroke
				(width 0.1)
				(type default)
			)
			(layer "B.Fab")
		)
		(fp_line
			(start 0.12065 0.3048)
			(end 0.67945 0.3048)
			(stroke
				(width 0.1)
				(type default)
			)
			(layer "B.Fab")
		)
		(fp_line
			(start -0.120396 0.3048)
			(end -0.120396 0.2794)
			(stroke
				(width 0.1)
				(type default)
			)
			(layer "B.Fab")
		)
		(fp_line
			(start -0.67945 0.3048)
			(end -0.120396 0.3048)
			(stroke
				(width 0.1)
				(type default)
			)
			(layer "B.Fab")
		)
		(pad "1" smd circle
			(at 0.40005 0 270)
			(size 0 0)
			(layers "B.Cu" "B.Mask" "B.Paste")
			(net "SMB_HOST_3V3AUX_SCL_R4")
		)
		(pad "2" smd circle
			(at -0.40005 0 270)
			(size 0 0)
			(layers "B.Cu" "B.Mask" "B.Paste")
			(net "SMB_HOST_3V3AUX_XDP_R_SCL")
		)
	)
	(footprint ""
		(layer "B.Cu")
		(at 137.08888 -9.362948 -90)
		(property "Reference" "R506"
			(at 0 0 90)
			(layer "B.SilkS")
			(hide yes)
			(effects
				(font
					(size 1.27 1.27)
				)
				(justify mirror)
			)
		)
		(property "Value" ""
			(at 0 0 90)
			(layer "B.Fab")
			(effects
				(font
					(size 1.27 1.27)
				)
				(justify mirror)
			)
		)
		(duplicate_pad_numbers_are_jumpers no)
		(fp_line
			(start -0.7874 0.4064)
			(end 0.7874 0.4064)
			(stroke
				(width 0.1524)
				(type default)
			)
			(layer "B.SilkS")
		)
		(fp_line
			(start 0.7874 0.4064)
			(end 0.7874 -0.4064)
			(stroke
				(width 0.1524)
				(type default)
			)
			(layer "B.SilkS")
		)
		(fp_line
			(start -0.7874 -0.4064)
			(end -0.7874 0.4064)
			(stroke
				(width 0.1524)
				(type default)
			)
			(layer "B.SilkS")
		)
		(fp_line
			(start 0.7874 -0.4064)
			(end -0.7874 -0.4064)
			(stroke
				(width 0.1524)
				(type default)
			)
			(layer "B.SilkS")
		)
		(fp_line
			(start -0.67945 0.3048)
			(end -0.120396 0.3048)
			(stroke
				(width 0.1)
				(type default)
			)
			(layer "B.Fab")
		)
		(fp_line
			(start -0.120396 0.3048)
			(end -0.120396 0.2794)
			(stroke
				(width 0.1)
				(type default)
			)
			(layer "B.Fab")
		)
		(fp_line
			(start 0.12065 0.3048)
			(end 0.67945 0.3048)
			(stroke
				(width 0.1)
				(type default)
			)
			(layer "B.Fab")
		)
		(fp_line
			(start 0.67945 0.3048)
			(end 0.67945 -0.305054)
			(stroke
				(width 0.1)
				(type default)
			)
			(layer "B.Fab")
		)
		(fp_line
			(start -0.120396 0.2794)
			(end 0.12065 0.2794)
			(stroke
				(width 0.1)
				(type default)
			)
			(layer "B.Fab")
		)
		(fp_line
			(start 0.12065 0.2794)
			(end 0.12065 0.3048)
			(stroke
				(width 0.1)
				(type default)
			)
			(layer "B.Fab")
		)
		(fp_line
			(start -0.12065 -0.2794)
			(end -0.12065 -0.3048)
			(stroke
				(width 0.1)
				(type default)
			)
			(layer "B.Fab")
		)
		(fp_line
			(start 0.12065 -0.2794)
			(end -0.12065 -0.2794)
			(stroke
				(width 0.1)
				(type default)
			)
			(layer "B.Fab")
		)
		(fp_line
			(start -0.67945 -0.3048)
			(end -0.67945 0.3048)
			(stroke
				(width 0.1)
				(type default)
			)
			(layer "B.Fab")
		)
		(fp_line
			(start -0.12065 -0.3048)
			(end -0.67945 -0.3048)
			(stroke
				(width 0.1)
				(type default)
			)
			(layer "B.Fab")
		)
		(fp_line
			(start 0.12065 -0.305054)
			(end 0.12065 -0.2794)
			(stroke
				(width 0.1)
				(type default)
			)
			(layer "B.Fab")
		)
		(fp_line
			(start 0.67945 -0.305054)
			(end 0.12065 -0.305054)
			(stroke
				(width 0.1)
				(type default)
			)
			(layer "B.Fab")
		)
		(pad "1" smd circle
			(at 0.40005 0 90)
			(size 0 0)
			(layers "B.Cu" "B.Mask" "B.Paste")
			(net "IRQ_SMI_ACTIVE_BMC_N")
		)
		(pad "2" smd circle
			(at -0.40005 0 90)
			(size 0 0)
			(layers "B.Cu" "B.Mask" "B.Paste")
			(net "IRQ0_A57")
		)
	)
	(footprint ""
		(layer "B.Cu")
		(at 407.90368 -184.165748 180)
		(property "Reference" "PR4226"
			(at 0 0 0)
			(layer "B.SilkS")
			(hide yes)
			(effects
				(font
					(size 1.27 1.27)
				)
				(justify mirror)
			)
		)
		(property "Value" ""
			(at 0 0 0)
			(layer "B.Fab")
			(effects
				(font
					(size 1.27 1.27)
				)
				(justify mirror)
			)
		)
		(duplicate_pad_numbers_are_jumpers no)
		(fp_line
			(start 0.7874 0.4064)
			(end 0.7874 -0.4064)
			(stroke
				(width 0.1524)
				(type default)
			)
			(layer "B.SilkS")
		)
		(fp_line
			(start 0.7874 -0.4064)
			(end -0.7874 -0.4064)
			(stroke
				(width 0.1524)
				(type default)
			)
			(layer "B.SilkS")
		)
		(fp_line
			(start -0.7874 0.4064)
			(end 0.7874 0.4064)
			(stroke
				(width 0.1524)
				(type default)
			)
			(layer "B.SilkS")
		)
		(fp_line
			(start -0.7874 -0.4064)
			(end -0.7874 0.4064)
			(stroke
				(width 0.1524)
				(type default)
			)
			(layer "B.SilkS")
		)
		(fp_line
			(start 0.67945 0.3048)
			(end 0.67945 -0.305054)
			(stroke
				(width 0.1)
				(type default)
			)
			(layer "B.Fab")
		)
		(fp_line
			(start 0.67945 -0.305054)
			(end 0.12065 -0.305054)
			(stroke
				(width 0.1)
				(type default)
			)
			(layer "B.Fab")
		)
		(fp_line
			(start 0.12065 0.3048)
			(end 0.67945 0.3048)
			(stroke
				(width 0.1)
				(type default)
			)
			(layer "B.Fab")
		)
		(fp_line
			(start 0.12065 0.2794)
			(end 0.12065 0.3048)
			(stroke
				(width 0.1)
				(type default)
			)
			(layer "B.Fab")
		)
		(fp_line
			(start 0.12065 -0.2794)
			(end -0.12065 -0.2794)
			(stroke
				(width 0.1)
				(type default)
			)
			(layer "B.Fab")
		)
		(fp_line
			(start 0.12065 -0.305054)
			(end 0.12065 -0.2794)
			(stroke
				(width 0.1)
				(type default)
			)
			(layer "B.Fab")
		)
		(fp_line
			(start -0.120396 0.3048)
			(end -0.120396 0.2794)
			(stroke
				(width 0.1)
				(type default)
			)
			(layer "B.Fab")
		)
		(fp_line
			(start -0.120396 0.2794)
			(end 0.12065 0.2794)
			(stroke
				(width 0.1)
				(type default)
			)
			(layer "B.Fab")
		)
		(fp_line
			(start -0.12065 -0.2794)
			(end -0.12065 -0.3048)
			(stroke
				(width 0.1)
				(type default)
			)
			(layer "B.Fab")
		)
		(fp_line
			(start -0.12065 -0.3048)
			(end -0.67945 -0.3048)
			(stroke
				(width 0.1)
				(type default)
			)
			(layer "B.Fab")
		)
		(fp_line
			(start -0.67945 0.3048)
			(end -0.120396 0.3048)
			(stroke
				(width 0.1)
				(type default)
			)
			(layer "B.Fab")
		)
		(fp_line
			(start -0.67945 -0.3048)
			(end -0.67945 0.3048)
			(stroke
				(width 0.1)
				(type default)
			)
			(layer "B.Fab")
		)
		(pad "1" smd circle
			(at 0.40005 0)
			(size 0 0)
			(layers "B.Cu" "B.Mask" "B.Paste")
			(net "PVCCINFAON_CPU0")
		)
		(pad "2" smd circle
			(at -0.40005 0)
			(size 0 0)
			(layers "B.Cu" "B.Mask" "B.Paste")
			(net "GND")
		)
	)
	(footprint ""
		(layer "B.Cu")
		(at 211.85378 -2.159 180)
		(property "Reference" "J74"
			(at 4.23545 -1.143 270)
			(unlocked yes)
			(layer "B.SilkS")
			(effects
				(font
					(size 0.7874 0.5842)
					(thickness 0.1524)
				)
				(justify left mirror)
			)
		)
		(property "Value" ""
			(at 0 0 0)
			(layer "B.Fab")
			(effects
				(font
					(size 1.27 1.27)
				)
				(justify mirror)
			)
		)
		(duplicate_pad_numbers_are_jumpers no)
		(fp_line
			(start 1.2192 2.1082)
			(end 1.2192 -2.1082)
			(stroke
				(width 0.1524)
				(type default)
			)
			(layer "B.SilkS")
		)
		(fp_line
			(start 1.2192 -2.1082)
			(end -1.2192 -2.1082)
			(stroke
				(width 0.1524)
				(type default)
			)
			(layer "B.SilkS")
		)
		(fp_line
			(start -1.2192 2.1082)
			(end 1.2192 2.1082)
			(stroke
				(width 0.1524)
				(type default)
			)
			(layer "B.SilkS")
		)
		(fp_line
			(start -1.2192 -2.1082)
			(end -1.2192 2.1082)
			(stroke
				(width 0.1524)
				(type default)
			)
			(layer "B.SilkS")
		)
		(pad "" np_thru_hole circle
			(at -3.4671 -1.27 90)
			(size 1.0414 1.0414)
			(drill 1.0414)
			(layers "*.Cu" "*.Mask")
			(clearance 0.381)
			(thermal_gap 0.381)
		)
		(pad "" np_thru_hole circle
			(at -3.4671 1.27 90)
			(size 1.0414 1.0414)
			(drill 1.0414)
			(layers "*.Cu" "*.Mask")
			(clearance 0.381)
			(thermal_gap 0.381)
		)
		(pad "" np_thru_hole circle
			(at 2.8829 -1.27 90)
			(size 1.0414 1.0414)
			(drill 1.0414)
			(layers "*.Cu" "*.Mask")
			(clearance 0.381)
			(thermal_gap 0.381)
		)
		(pad "" np_thru_hole circle
			(at 2.8829 1.27 90)
			(size 1.0414 1.0414)
			(drill 1.0414)
			(layers "*.Cu" "*.Mask")
			(clearance 0.381)
			(thermal_gap 0.381)
		)
		(pad "1" smd rect
			(at -0.8255 -0.249936 90)
			(size 0.3048 0.508)
			(layers "B.Cu" "B.Mask" "B.Paste")
			(net "DELTA_L_85_5INCH_IN4_DN")
		)
		(pad "2" smd rect
			(at -0.8255 0.249936 90)
			(size 0.3048 0.508)
			(layers "B.Cu" "B.Mask" "B.Paste")
			(net "DELTA_L_85_5INCH_IN4_DP")
		)
		(pad "3" smd circle
			(at 0 0)
			(size 0 0)
			(layers "B.Cu" "B.Mask" "B.Paste")
			(net "DELTA_L_GND_1")
		)
		(zone
			(layers "F.Cu" "B.Cu" "In1.Cu" "In2.Cu" "In3.Cu" "In4.Cu" "In5.Cu" "In6.Cu"
				"In7.Cu" "In8.Cu" "In9.Cu" "In10.Cu" "In11.Cu" "In12.Cu" "In13.Cu" "In14.Cu"
				"In15.Cu" "In16.Cu"
			)
			(hatch none 0.5)
			(connect_pads
				(clearance 0)
			)
			(min_thickness 0.25)
			(keepout
				(tracks not_allowed)
				(vias allowed)
				(pads allowed)
				(copperpour not_allowed)
				(footprints allowed)
			)
			(placement
				(enabled no)
				(sheetname "")
			)
			(fill
				(thermal_gap 0.5)
				(thermal_bridge_width 0.5)
				(island_removal_mode 0)
			)
			(polygon
				(pts
					(arc
						(start 209.89798 -3.429)
						(mid 208.04378 -3.429)
						(end 209.89798 -3.429)
					)
				)
			)
		)
		(zone
			(layers "F.Cu" "B.Cu" "In1.Cu" "In2.Cu" "In3.Cu" "In4.Cu" "In5.Cu" "In6.Cu"
				"In7.Cu" "In8.Cu" "In9.Cu" "In10.Cu" "In11.Cu" "In12.Cu" "In13.Cu" "In14.Cu"
				"In15.Cu" "In16.Cu"
			)
			(hatch none 0.5)
			(connect_pads
				(clearance 0)
			)
			(min_thickness 0.25)
			(keepout
				(tracks not_allowed)
				(vias allowed)
				(pads allowed)
				(copperpour not_allowed)
				(footprints allowed)
			)
			(placement
				(enabled no)
				(sheetname "")
			)
			(fill
				(thermal_gap 0.5)
				(thermal_bridge_width 0.5)
				(island_removal_mode 0)
			)
			(polygon
				(pts
					(arc
						(start 209.89798 -0.889)
						(mid 208.04378 -0.889)
						(end 209.89798 -0.889)
					)
				)
			)
		)
		(zone
			(layers "F.Cu" "B.Cu" "In1.Cu" "In2.Cu" "In3.Cu" "In4.Cu" "In5.Cu" "In6.Cu"
				"In7.Cu" "In8.Cu" "In9.Cu" "In10.Cu" "In11.Cu" "In12.Cu" "In13.Cu" "In14.Cu"
				"In15.Cu" "In16.Cu"
			)
			(hatch none 0.5)
			(connect_pads
				(clearance 0)
			)
			(min_thickness 0.25)
			(keepout
				(tracks not_allowed)
				(vias allowed)
				(pads allowed)
				(copperpour not_allowed)
				(footprints allowed)
			)
			(placement
				(enabled no)
				(sheetname "")
			)
			(fill
				(thermal_gap 0.5)
				(thermal_bridge_width 0.5)
				(island_removal_mode 0)
			)
			(polygon
				(pts
					(arc
						(start 216.24798 -3.429)
						(mid 214.39378 -3.429)
						(end 216.24798 -3.429)
					)
				)
			)
		)
		(zone
			(layers "F.Cu" "B.Cu" "In1.Cu" "In2.Cu" "In3.Cu" "In4.Cu" "In5.Cu" "In6.Cu"
				"In7.Cu" "In8.Cu" "In9.Cu" "In10.Cu" "In11.Cu" "In12.Cu" "In13.Cu" "In14.Cu"
				"In15.Cu" "In16.Cu"
			)
			(hatch none 0.5)
			(connect_pads
				(clearance 0)
			)
			(min_thickness 0.25)
			(keepout
				(tracks not_allowed)
				(vias allowed)
				(pads allowed)
				(copperpour not_allowed)
				(footprints allowed)
			)
			(placement
				(enabled no)
				(sheetname "")
			)
			(fill
				(thermal_gap 0.5)
				(thermal_bridge_width 0.5)
				(island_removal_mode 0)
			)
			(polygon
				(pts
					(arc
						(start 216.24798 -0.889)
						(mid 214.39378 -0.889)
						(end 216.24798 -0.889)
					)
				)
			)
		)
		(zone
			(layer "B.Cu")
			(hatch none 0.5)
			(connect_pads
				(clearance 0)
			)
			(min_thickness 0.25)
			(keepout
				(tracks not_allowed)
				(vias allowed)
				(pads allowed)
				(copperpour not_allowed)
				(footprints allowed)
			)
			(placement
				(enabled no)
				(sheetname "")
			)
			(fill
				(thermal_gap 0.5)
				(thermal_bridge_width 0.5)
				(island_removal_mode 0)
			)
			(polygon
				(pts
					(xy 212.97138 -1.61036) (xy 212.97138 -1.705864) (xy 212.37448 -1.705864) (xy 212.37448 -2.112264)
					(xy 212.97138 -2.112264) (xy 212.97138 -2.205736) (xy 212.37448 -2.205736) (xy 212.37448 -2.612136)
					(xy 212.97138 -2.612136) (xy 212.97138 -2.70764) (xy 212.27288 -2.70764) (xy 212.27288 -1.61036)
				)
			)
		)
	)
)
